(kicad_pcb
	(version 20260206)
	(generator "pcbnew")
	(generator_version "10.0")
	(general
		(thickness 1.6)
		(legacy_teardrops no)
	)
	(paper "A4")
	(title_block
		(title "v1-chassis-manager — T6M_CM_d_v01_1031_1645.brd")
		(comment 1 "Open CloudServer (Microsoft) / footprints 246-253 of 2512")
	)
	(layers
		(0 "F.Cu" signal "TOP")
		(4 "In1.Cu" signal "GND1")
		(6 "In2.Cu" signal "IN1")
		(8 "In3.Cu" signal "VCC1")
		(10 "In4.Cu" signal "VCC2")
		(12 "In5.Cu" signal "GND2")
		(14 "In6.Cu" signal "IN2")
		(16 "In7.Cu" signal "IN3")
		(18 "In8.Cu" signal "GND3")
		(2 "B.Cu" signal "BOTTOM")
		(9 "F.Adhes" user "F.Adhesive")
		(11 "B.Adhes" user "B.Adhesive")
		(13 "F.Paste" user "Package Geometry/Pastemask Top")
		(15 "B.Paste" user "Package Geometry/Pastemask Bottom")
		(5 "F.SilkS" user "Ref Des/Silkscreen Top")
		(7 "B.SilkS" user "Ref Des/Silkscreen Bottom")
		(1 "F.Mask" user "Board Geometry/Soldermask Top")
		(3 "B.Mask" user "Board Geometry/Soldermask Bottom")
		(17 "Dwgs.User" user "User.Drawings")
		(19 "Cmts.User" user "User.Comments")
		(21 "Eco1.User" user "User.Eco1")
		(23 "Eco2.User" user "User.Eco2")
		(25 "Edge.Cuts" user "Board Geometry/Outline")
		(27 "Margin" user)
		(31 "F.CrtYd" user "Package Geometry/Place Bound Top")
		(29 "B.CrtYd" user "Package Geometry/Place Bound Bottom")
		(35 "F.Fab" user "Ref Des/Assembly Top")
		(33 "B.Fab" user "Ref Des/Assembly Bottom")
	)
	(footprint ""
		(layer "F.Cu")
		(at 11.889994 -29.778706 90)
		(property "Reference" "R654"
			(at -1.126744 -1.052322 90)
			(unlocked yes)
			(layer "F.SilkS")
			(effects
				(font
					(size 0.7874 0.5842)
					(thickness 0.1524)
				)
				(justify left)
			)
		)
		(property "Value" ""
			(at 0 0 90)
			(layer "F.Fab")
			(effects
				(font
					(size 1.27 1.27)
				)
			)
		)
		(duplicate_pad_numbers_are_jumpers no)
		(fp_line
			(start 0.7874 -0.4064)
			(end 0.7874 0.4064)
			(stroke
				(width 0.1524)
				(type default)
			)
			(layer "F.SilkS")
		)
		(fp_line
			(start -0.7874 -0.4064)
			(end 0.7874 -0.4064)
			(stroke
				(width 0.1524)
				(type default)
			)
			(layer "F.SilkS")
		)
		(fp_line
			(start 0.7874 0.4064)
			(end -0.7874 0.4064)
			(stroke
				(width 0.1524)
				(type default)
			)
			(layer "F.SilkS")
		)
		(fp_line
			(start -0.7874 0.4064)
			(end -0.7874 -0.4064)
			(stroke
				(width 0.1524)
				(type default)
			)
			(layer "F.SilkS")
		)
		(fp_poly
			(pts
				(xy -0.508 0.2794) (xy -0.508 0.2286) (xy -0.635 0.2286) (xy -0.635 -0.254) (xy -0.5334 -0.254)
				(xy -0.5334 -0.2794) (xy 0.5334 -0.2794) (xy 0.5334 -0.254) (xy 0.635 -0.254) (xy 0.635 0.254) (xy 0.5334 0.254)
				(xy 0.5334 0.2794)
			)
			(stroke
				(width 0)
				(type default)
			)
			(fill no)
			(layer "F.CrtYd")
		)
		(pad "1" smd rect
			(at 0.40005 0 90)
			(size 0.4572 0.508)
			(layers "F.Cu" "F.Mask" "F.Paste")
			(net "GND")
		)
		(pad "2" smd rect
			(at -0.40005 0 90)
			(size 0.4572 0.508)
			(layers "F.Cu" "F.Mask" "F.Paste")
			(net "N54251449")
		)
	)
	(footprint ""
		(layer "F.Cu")
		(at 59.113166 -96.709992 -90)
		(property "Reference" "R55"
			(at 54.98719 -28.440888 90)
			(unlocked yes)
			(layer "F.SilkS")
			(effects
				(font
					(size 0.7874 0.5842)
					(thickness 0.1524)
				)
				(justify left)
			)
		)
		(property "Value" ""
			(at 0 0 270)
			(layer "F.Fab")
			(effects
				(font
					(size 1.27 1.27)
				)
			)
		)
		(duplicate_pad_numbers_are_jumpers no)
		(fp_line
			(start -0.7874 0.4064)
			(end -0.7874 -0.4064)
			(stroke
				(width 0.1524)
				(type default)
			)
			(layer "F.SilkS")
		)
		(fp_line
			(start 0.7874 0.4064)
			(end -0.7874 0.4064)
			(stroke
				(width 0.1524)
				(type default)
			)
			(layer "F.SilkS")
		)
		(fp_line
			(start -0.7874 -0.4064)
			(end 0.7874 -0.4064)
			(stroke
				(width 0.1524)
				(type default)
			)
			(layer "F.SilkS")
		)
		(fp_line
			(start 0.7874 -0.4064)
			(end 0.7874 0.4064)
			(stroke
				(width 0.1524)
				(type default)
			)
			(layer "F.SilkS")
		)
		(fp_poly
			(pts
				(xy -0.508 0.2794) (xy -0.508 0.2286) (xy -0.635 0.2286) (xy -0.635 -0.254) (xy -0.5334 -0.254)
				(xy -0.5334 -0.2794) (xy 0.5334 -0.2794) (xy 0.5334 -0.254) (xy 0.635 -0.254) (xy 0.635 0.254) (xy 0.5334 0.254)
				(xy 0.5334 0.2794)
			)
			(stroke
				(width 0)
				(type default)
			)
			(fill no)
			(layer "F.CrtYd")
		)
		(pad "1" smd rect
			(at 0.40005 0 270)
			(size 0.4572 0.508)
			(layers "F.Cu" "F.Mask" "F.Paste")
			(net "PD_CPU_NODE1_DFX_GPIO_GRP1_1")
		)
		(pad "2" smd rect
			(at -0.40005 0 270)
			(size 0.4572 0.508)
			(layers "F.Cu" "F.Mask" "F.Paste")
			(net "GND")
		)
	)
	(footprint ""
		(layer "F.Cu")
		(at 184.3786 -180.7972)
		(property "Reference" "R1321"
			(at 9.3218 17.12087 0)
			(unlocked yes)
			(layer "F.SilkS")
			(effects
				(font
					(size 0.7874 0.5842)
					(thickness 0.1524)
				)
				(justify left)
			)
		)
		(property "Value" ""
			(at 0 0 0)
			(layer "F.Fab")
			(effects
				(font
					(size 1.27 1.27)
				)
			)
		)
		(duplicate_pad_numbers_are_jumpers no)
		(fp_line
			(start -0.7874 -0.4064)
			(end 0.7874 -0.4064)
			(stroke
				(width 0.1524)
				(type default)
			)
			(layer "F.SilkS")
		)
		(fp_line
			(start -0.7874 0.4064)
			(end -0.7874 -0.4064)
			(stroke
				(width 0.1524)
				(type default)
			)
			(layer "F.SilkS")
		)
		(fp_line
			(start 0.7874 -0.4064)
			(end 0.7874 0.4064)
			(stroke
				(width 0.1524)
				(type default)
			)
			(layer "F.SilkS")
		)
		(fp_line
			(start 0.7874 0.4064)
			(end -0.7874 0.4064)
			(stroke
				(width 0.1524)
				(type default)
			)
			(layer "F.SilkS")
		)
		(fp_poly
			(pts
				(xy -0.508 0.2794) (xy -0.508 0.2286) (xy -0.635 0.2286) (xy -0.635 -0.254) (xy -0.5334 -0.254)
				(xy -0.5334 -0.2794) (xy 0.5334 -0.2794) (xy 0.5334 -0.254) (xy 0.635 -0.254) (xy 0.635 0.254) (xy 0.5334 0.254)
				(xy 0.5334 0.2794)
			)
			(stroke
				(width 0)
				(type default)
			)
			(fill no)
			(layer "F.CrtYd")
		)
		(pad "1" smd rect
			(at 0.40005 0)
			(size 0.4572 0.508)
			(layers "F.Cu" "F.Mask" "F.Paste")
			(net "POWER_SW3_PWR_CTR_12V")
		)
		(pad "2" smd rect
			(at -0.40005 0)
			(size 0.4572 0.508)
			(layers "F.Cu" "F.Mask" "F.Paste")
			(net "POWER_SW3_PWR_CTR_12V_R")
		)
	)
	(footprint ""
		(layer "F.Cu")
		(at 120.496838 -151.266906 90)
		(property "Reference" "R1039"
			(at -1.702308 2.418842 90)
			(unlocked yes)
			(layer "F.SilkS")
			(effects
				(font
					(size 0.635 0.4064)
					(thickness 0.1524)
				)
				(justify left)
			)
		)
		(property "Value" ""
			(at 0 0 90)
			(layer "F.Fab")
			(effects
				(font
					(size 1.27 1.27)
				)
			)
		)
		(duplicate_pad_numbers_are_jumpers no)
		(fp_line
			(start 0.7874 -0.4064)
			(end 0.7874 0.4064)
			(stroke
				(width 0.1524)
				(type default)
			)
			(layer "F.SilkS")
		)
		(fp_line
			(start -0.7874 -0.4064)
			(end 0.7874 -0.4064)
			(stroke
				(width 0.1524)
				(type default)
			)
			(layer "F.SilkS")
		)
		(fp_line
			(start 0.7874 0.4064)
			(end -0.7874 0.4064)
			(stroke
				(width 0.1524)
				(type default)
			)
			(layer "F.SilkS")
		)
		(fp_line
			(start -0.7874 0.4064)
			(end -0.7874 -0.4064)
			(stroke
				(width 0.1524)
				(type default)
			)
			(layer "F.SilkS")
		)
		(fp_poly
			(pts
				(xy -0.508 0.2794) (xy -0.508 0.2286) (xy -0.635 0.2286) (xy -0.635 -0.254) (xy -0.5334 -0.254)
				(xy -0.5334 -0.2794) (xy 0.5334 -0.2794) (xy 0.5334 -0.254) (xy 0.635 -0.254) (xy 0.635 0.254) (xy 0.5334 0.254)
				(xy 0.5334 0.2794)
			)
			(stroke
				(width 0)
				(type default)
			)
			(fill no)
			(layer "F.CrtYd")
		)
		(pad "1" smd rect
			(at 0.40005 0 90)
			(size 0.4572 0.508)
			(layers "F.Cu" "F.Mask" "F.Paste")
			(net "N52998343")
		)
		(pad "2" smd rect
			(at -0.40005 0 90)
			(size 0.4572 0.508)
			(layers "F.Cu" "F.Mask" "F.Paste")
			(net "P12V_AUX")
		)
	)
	(footprint ""
		(layer "F.Cu")
		(at 65.751202 -162.729926)
		(property "Reference" "Q35"
			(at 7.759446 1.055624 90)
			(unlocked yes)
			(layer "F.SilkS")
			(effects
				(font
					(size 0.7874 0.5842)
					(thickness 0.1524)
				)
			)
		)
		(property "Value" ""
			(at 0 0 0)
			(layer "F.Fab")
			(effects
				(font
					(size 1.27 1.27)
				)
			)
		)
		(duplicate_pad_numbers_are_jumpers no)
		(fp_line
			(start -0.100076 -0.525018)
			(end 1.044448 -0.525018)
			(stroke
				(width 0.1524)
				(type default)
			)
			(layer "F.SilkS")
		)
		(fp_line
			(start -0.100076 -0.320294)
			(end -0.100076 -0.525018)
			(stroke
				(width 0.1524)
				(type default)
			)
			(layer "F.SilkS")
		)
		(fp_line
			(start -0.100076 2.474976)
			(end -0.100076 2.295906)
			(stroke
				(width 0.1524)
				(type default)
			)
			(layer "F.SilkS")
		)
		(fp_line
			(start 1.044448 2.474976)
			(end -0.100076 2.474976)
			(stroke
				(width 0.1524)
				(type default)
			)
			(layer "F.SilkS")
		)
		(fp_line
			(start 1.755648 -0.525018)
			(end 2.899918 -0.525018)
			(stroke
				(width 0.1524)
				(type default)
			)
			(layer "F.SilkS")
		)
		(fp_line
			(start 2.899918 -0.525018)
			(end 2.899918 -0.345694)
			(stroke
				(width 0.1524)
				(type default)
			)
			(layer "F.SilkS")
		)
		(fp_line
			(start 2.899918 2.295906)
			(end 2.899918 2.474976)
			(stroke
				(width 0.1524)
				(type default)
			)
			(layer "F.SilkS")
		)
		(fp_line
			(start 2.899918 2.474976)
			(end 1.755648 2.474976)
			(stroke
				(width 0.1524)
				(type default)
			)
			(layer "F.SilkS")
		)
		(fp_poly
			(pts
				(xy -0.10795 -1.347724) (xy 0.410972 -1.347724) (xy 0.14732 -0.770382)
			)
			(stroke
				(width 0)
				(type default)
			)
			(fill yes)
			(layer "F.SilkS")
		)
		(fp_poly
			(pts
				(xy -0.100076 -0.525018) (xy -0.100076 -0.244094) (xy -0.301752 -0.244094) (xy -0.301752 2.194306)
				(xy -0.100076 2.194306) (xy -0.100076 2.474976) (xy 1.120648 2.474976) (xy 1.120648 2.651506) (xy 1.679448 2.651506)
				(xy 1.679448 2.474976) (xy 2.899918 2.474976) (xy 2.899918 2.219706) (xy 3.101848 2.219706) (xy 3.101848 -0.269494)
				(xy 2.899918 -0.269494) (xy 2.899918 -0.525018) (xy 1.679448 -0.525018) (xy 1.679448 -0.701294)
				(xy 1.120648 -0.701294) (xy 1.120648 -0.525018)
			)
			(stroke
				(width 0)
				(type default)
			)
			(fill no)
			(layer "F.CrtYd")
		)
		(fp_line
			(start -0.100076 -0.525018)
			(end 2.899918 -0.525018)
			(stroke
				(width 0.1)
				(type default)
			)
			(layer "F.Fab")
		)
		(fp_line
			(start -0.100076 2.474976)
			(end -0.100076 -0.525018)
			(stroke
				(width 0.1)
				(type default)
			)
			(layer "F.Fab")
		)
		(fp_line
			(start 2.899918 -0.525018)
			(end 2.899918 2.474976)
			(stroke
				(width 0.1)
				(type default)
			)
			(layer "F.Fab")
		)
		(fp_line
			(start 2.899918 2.474976)
			(end -0.100076 2.474976)
			(stroke
				(width 0.1)
				(type default)
			)
			(layer "F.Fab")
		)
		(pad "1" smd rect
			(at 0 0 270)
			(size 0.3556 0.508)
			(layers "F.Cu" "F.Mask" "F.Paste")
			(net "P5V_NODE1")
		)
		(pad "2" smd rect
			(at 0 0.649986 270)
			(size 0.3556 0.508)
			(layers "F.Cu" "F.Mask" "F.Paste")
			(net "P5V_NODE1")
		)
		(pad "3" smd rect
			(at 0 1.299972 270)
			(size 0.3556 0.508)
			(layers "F.Cu" "F.Mask" "F.Paste")
			(net "P5V_NODE1")
		)
		(pad "4" smd rect
			(at 0 1.949958 270)
			(size 0.3556 0.508)
			(layers "F.Cu" "F.Mask" "F.Paste")
			(net "FM_CPLD_NODE1_P5V_EN_LV")
		)
		(pad "5" smd custom
			(at 1.400048 0.975106 270)
			(size 0.569976 0.569976)
			(layers "F.Cu" "F.Mask" "F.Paste")
			(net "P5V_STB_NODE1")
			(options
				(clearance outline)
				(anchor circle)
			)
			(primitives
				(gr_poly
					(pts
						(xy -1.225042 1.139952) (xy -1.225042 0.724916) (xy -1.605026 0.724916) (xy -1.605026 0.295148)
						(xy -1.225042 0.295148) (xy -1.225042 -0.839978) (xy -1.175004 -0.839978) (xy -1.175004 -1.139952)
						(xy -0.774954 -1.139952) (xy -0.774954 -0.839978) (xy -0.525018 -0.839978) (xy -0.525018 -1.139952)
						(xy -0.124968 -1.139952) (xy -0.124968 -0.839978) (xy 0.124968 -0.839978) (xy 0.124968 -1.139952)
						(xy 0.525018 -1.139952) (xy 0.525018 -0.839978) (xy 0.774954 -0.839978) (xy 0.774954 -1.139952)
						(xy 1.175004 -1.139952) (xy 1.175004 -0.839978) (xy 1.225042 -0.839978) (xy 1.225042 0.295148)
						(xy 1.605026 0.295148) (xy 1.605026 0.724916) (xy 1.225042 0.724916) (xy 1.225042 1.139952)
					)
					(width 0)
					(fill yes)
				)
			)
		)
		(zone
			(layer "F.Cu")
			(hatch none 0.5)
			(connect_pads
				(clearance 0)
			)
			(min_thickness 0.25)
			(keepout
				(tracks not_allowed)
				(vias allowed)
				(pads allowed)
				(copperpour not_allowed)
				(footprints allowed)
			)
			(placement
				(enabled no)
				(sheetname "")
			)
			(fill
				(thermal_gap 0.5)
				(thermal_bridge_width 0.5)
				(island_removal_mode 0)
			)
			(polygon
				(pts
					(xy 66.08445 -163.25342) (xy 66.08445 -160.25622) (xy 66.46545 -160.25622) (xy 66.46545 -163.25342)
				)
			)
		)
		(zone
			(layer "F.Cu")
			(hatch none 0.5)
			(connect_pads
				(clearance 0)
			)
			(min_thickness 0.25)
			(keepout
				(tracks allowed)
				(vias not_allowed)
				(pads allowed)
				(copperpour not_allowed)
				(footprints allowed)
			)
			(placement
				(enabled no)
				(sheetname "")
			)
			(fill
				(thermal_gap 0.5)
				(thermal_bridge_width 0.5)
				(island_removal_mode 0)
			)
			(polygon
				(pts
					(xy 66.46545 -163.25342) (xy 66.46545 -160.25622) (xy 66.08445 -160.25622) (xy 66.08445 -163.25342)
				)
			)
		)
	)
	(footprint ""
		(layer "F.Cu")
		(at 62.028324 -98.542856 180)
		(property "Reference" "R1093"
			(at -24.628094 -53.301646 0)
			(unlocked yes)
			(layer "F.SilkS")
			(effects
				(font
					(size 0.7874 0.5842)
					(thickness 0.1524)
				)
				(justify left)
			)
		)
		(property "Value" ""
			(at 0 0 180)
			(layer "F.Fab")
			(effects
				(font
					(size 1.27 1.27)
				)
			)
		)
		(duplicate_pad_numbers_are_jumpers no)
		(fp_line
			(start 0.7874 0.4064)
			(end -0.7874 0.4064)
			(stroke
				(width 0.1524)
				(type default)
			)
			(layer "F.SilkS")
		)
		(fp_line
			(start 0.7874 -0.4064)
			(end 0.7874 0.4064)
			(stroke
				(width 0.1524)
				(type default)
			)
			(layer "F.SilkS")
		)
		(fp_line
			(start -0.7874 0.4064)
			(end -0.7874 -0.4064)
			(stroke
				(width 0.1524)
				(type default)
			)
			(layer "F.SilkS")
		)
		(fp_line
			(start -0.7874 -0.4064)
			(end 0.7874 -0.4064)
			(stroke
				(width 0.1524)
				(type default)
			)
			(layer "F.SilkS")
		)
		(fp_poly
			(pts
				(xy -0.508 0.2794) (xy -0.508 0.2286) (xy -0.635 0.2286) (xy -0.635 -0.254) (xy -0.5334 -0.254)
				(xy -0.5334 -0.2794) (xy 0.5334 -0.2794) (xy 0.5334 -0.254) (xy 0.635 -0.254) (xy 0.635 0.254) (xy 0.5334 0.254)
				(xy 0.5334 0.2794)
			)
			(stroke
				(width 0)
				(type default)
			)
			(fill no)
			(layer "F.CrtYd")
		)
		(pad "1" smd rect
			(at 0.40005 0 180)
			(size 0.4572 0.508)
			(layers "F.Cu" "F.Mask" "F.Paste")
			(net "GND")
		)
		(pad "2" smd rect
			(at -0.40005 0 180)
			(size 0.4572 0.508)
			(layers "F.Cu" "F.Mask" "F.Paste")
			(net "P1V8_SUS_NODE1")
		)
	)
	(footprint ""
		(layer "F.Cu")
		(at 90.814398 -176.562512 180)
		(property "Reference" "R1178"
			(at -85.972142 -76.337414 0)
			(unlocked yes)
			(layer "F.SilkS")
			(effects
				(font
					(size 0.7874 0.5842)
					(thickness 0.1524)
				)
				(justify left)
			)
		)
		(property "Value" ""
			(at 0 0 180)
			(layer "F.Fab")
			(effects
				(font
					(size 1.27 1.27)
				)
			)
		)
		(duplicate_pad_numbers_are_jumpers no)
		(fp_line
			(start 0.7874 0.4064)
			(end -0.7874 0.4064)
			(stroke
				(width 0.1524)
				(type default)
			)
			(layer "F.SilkS")
		)
		(fp_line
			(start 0.7874 -0.4064)
			(end 0.7874 0.4064)
			(stroke
				(width 0.1524)
				(type default)
			)
			(layer "F.SilkS")
		)
		(fp_line
			(start -0.7874 0.4064)
			(end -0.7874 -0.4064)
			(stroke
				(width 0.1524)
				(type default)
			)
			(layer "F.SilkS")
		)
		(fp_line
			(start -0.7874 -0.4064)
			(end 0.7874 -0.4064)
			(stroke
				(width 0.1524)
				(type default)
			)
			(layer "F.SilkS")
		)
		(fp_poly
			(pts
				(xy -0.508 0.2794) (xy -0.508 0.2286) (xy -0.635 0.2286) (xy -0.635 -0.254) (xy -0.5334 -0.254)
				(xy -0.5334 -0.2794) (xy 0.5334 -0.2794) (xy 0.5334 -0.254) (xy 0.635 -0.254) (xy 0.635 0.254) (xy 0.5334 0.254)
				(xy 0.5334 0.2794)
			)
			(stroke
				(width 0)
				(type default)
			)
			(fill no)
			(layer "F.CrtYd")
		)
		(pad "1" smd rect
			(at 0.40005 0 180)
			(size 0.4572 0.508)
			(layers "F.Cu" "F.Mask" "F.Paste")
			(net "CPLD_UART_RTS_P4_N")
		)
		(pad "2" smd rect
			(at -0.40005 0 180)
			(size 0.4572 0.508)
			(layers "F.Cu" "F.Mask" "F.Paste")
			(net "GND")
		)
	)
	(footprint ""
		(layer "F.Cu")
		(at 113.730532 -132.012944 90)
		(property "Reference" "PR58"
			(at -0.690372 5.281676 90)
			(unlocked yes)
			(layer "F.SilkS")
			(effects
				(font
					(size 0.7874 0.5842)
					(thickness 0.1524)
				)
				(justify left)
			)
		)
		(property "Value" ""
			(at 0 0 90)
			(layer "F.Fab")
			(effects
				(font
					(size 1.27 1.27)
				)
			)
		)
		(duplicate_pad_numbers_are_jumpers no)
		(fp_line
			(start 0.7874 -0.4064)
			(end 0.7874 0.4064)
			(stroke
				(width 0.1524)
				(type default)
			)
			(layer "F.SilkS")
		)
		(fp_line
			(start -0.7874 -0.4064)
			(end 0.7874 -0.4064)
			(stroke
				(width 0.1524)
				(type default)
			)
			(layer "F.SilkS")
		)
		(fp_line
			(start 0.7874 0.4064)
			(end -0.7874 0.4064)
			(stroke
				(width 0.1524)
				(type default)
			)
			(layer "F.SilkS")
		)
		(fp_line
			(start -0.7874 0.4064)
			(end -0.7874 -0.4064)
			(stroke
				(width 0.1524)
				(type default)
			)
			(layer "F.SilkS")
		)
		(fp_poly
			(pts
				(xy -0.508 0.2794) (xy -0.508 0.2286) (xy -0.635 0.2286) (xy -0.635 -0.254) (xy -0.5334 -0.254)
				(xy -0.5334 -0.2794) (xy 0.5334 -0.2794) (xy 0.5334 -0.254) (xy 0.635 -0.254) (xy 0.635 0.254) (xy 0.5334 0.254)
				(xy 0.5334 0.2794)
			)
			(stroke
				(width 0)
				(type default)
			)
			(fill no)
			(layer "F.CrtYd")
		)
		(pad "1" smd rect
			(at 0.40005 0 90)
			(size 0.4572 0.508)
			(layers "F.Cu" "F.Mask" "F.Paste")
			(net "VR_PVCCP_NODE1_ISEN1P_CC")
		)
		(pad "2" smd rect
			(at -0.40005 0 90)
			(size 0.4572 0.508)
			(layers "F.Cu" "F.Mask" "F.Paste")
			(net "VR_PVCCP_NODE1_ISEN1P_RR")
		)
	)
)
